(kicad_pcb
	(version 20260206)
	(generator "pcbnew")
	(generator_version "10.0")
	(general
		(thickness 1.6)
		(legacy_teardrops no)
	)
	(paper "A4")
	(title_block
		(title "01162023_DA0F0TEBIF0_F0T_Expander_BD_F_brd_V02_OCP.brd")
		(comment 1 "Grand Teton / footprints 5526-5530 of 9728")
	)
	(layers
		(0 "F.Cu" signal "TOP")
		(4 "In1.Cu" signal "GND")
		(6 "In2.Cu" signal "VCC")
		(8 "In3.Cu" signal "VCC1")
		(10 "In4.Cu" signal "GND1")
		(12 "In5.Cu" signal "IN1")
		(14 "In6.Cu" signal "GND2")
		(16 "In7.Cu" signal "IN2")
		(18 "In8.Cu" signal "GND3")
		(20 "In9.Cu" signal "IN3")
		(22 "In10.Cu" signal "GND4")
		(24 "In11.Cu" signal "IN4")
		(26 "In12.Cu" signal "GND5")
		(28 "In13.Cu" signal "IN5")
		(30 "In14.Cu" signal "GND6")
		(32 "In15.Cu" signal "IN6")
		(34 "In16.Cu" signal "GND7")
		(2 "B.Cu" signal "BOTTOM")
		(9 "F.Adhes" user "F.Adhesive")
		(11 "B.Adhes" user "B.Adhesive")
		(13 "F.Paste" user "Package Geometry/Pastemask Top")
		(15 "B.Paste" user "Package Geometry/Pastemask Bottom")
		(5 "F.SilkS" user "Ref Des/Silkscreen Top")
		(7 "B.SilkS" user "Ref Des/Silkscreen Bottom")
		(1 "F.Mask" user "Board Geometry/Soldermask Top")
		(3 "B.Mask" user "Board Geometry/Soldermask Bottom")
		(17 "Dwgs.User" user "User.Drawings")
		(19 "Cmts.User" user "User.Comments")
		(21 "Eco1.User" user "User.Eco1")
		(23 "Eco2.User" user "User.Eco2")
		(25 "Edge.Cuts" user "Board Geometry/Outline")
		(27 "Margin" user)
		(31 "F.CrtYd" user "Package Geometry/Place Bound Top")
		(29 "B.CrtYd" user "Package Geometry/Place Bound Bottom")
		(35 "F.Fab" user "Ref Des/Assembly Top")
		(33 "B.Fab" user "Ref Des/Assembly Bottom")
	)
	(footprint ""
		(layer "F.Cu")
		(at 455.938128 -305.500024)
		(property "Reference" "PC270"
			(at 0 0 0)
			(layer "F.SilkS")
			(hide yes)
			(effects
				(font
					(size 1.27 1.27)
				)
			)
		)
		(property "Value" ""
			(at 0 0 0)
			(layer "F.Fab")
			(effects
				(font
					(size 1.27 1.27)
				)
			)
		)
		(duplicate_pad_numbers_are_jumpers no)
		(fp_line
			(start -0.7874 -0.4064)
			(end 0.7874 -0.4064)
			(stroke
				(width 0.1524)
				(type default)
			)
			(layer "F.SilkS")
		)
		(fp_line
			(start -0.7874 0.4064)
			(end -0.7874 -0.4064)
			(stroke
				(width 0.1524)
				(type default)
			)
			(layer "F.SilkS")
		)
		(fp_line
			(start 0.7874 -0.4064)
			(end 0.7874 0.4064)
			(stroke
				(width 0.1524)
				(type default)
			)
			(layer "F.SilkS")
		)
		(fp_line
			(start 0.7874 0.4064)
			(end -0.7874 0.4064)
			(stroke
				(width 0.1524)
				(type default)
			)
			(layer "F.SilkS")
		)
		(fp_line
			(start -0.67945 -0.305054)
			(end -0.12065 -0.305054)
			(stroke
				(width 0.1)
				(type default)
			)
			(layer "F.Fab")
		)
		(fp_line
			(start -0.67945 0.3048)
			(end -0.67945 -0.305054)
			(stroke
				(width 0.1)
				(type default)
			)
			(layer "F.Fab")
		)
		(fp_line
			(start -0.12065 -0.305054)
			(end -0.12065 -0.2794)
			(stroke
				(width 0.1)
				(type default)
			)
			(layer "F.Fab")
		)
		(fp_line
			(start -0.12065 -0.2794)
			(end 0.12065 -0.2794)
			(stroke
				(width 0.1)
				(type default)
			)
			(layer "F.Fab")
		)
		(fp_line
			(start -0.12065 0.2794)
			(end -0.12065 0.3048)
			(stroke
				(width 0.1)
				(type default)
			)
			(layer "F.Fab")
		)
		(fp_line
			(start -0.12065 0.3048)
			(end -0.67945 0.3048)
			(stroke
				(width 0.1)
				(type default)
			)
			(layer "F.Fab")
		)
		(fp_line
			(start 0.120396 0.2794)
			(end -0.12065 0.2794)
			(stroke
				(width 0.1)
				(type default)
			)
			(layer "F.Fab")
		)
		(fp_line
			(start 0.120396 0.3048)
			(end 0.120396 0.2794)
			(stroke
				(width 0.1)
				(type default)
			)
			(layer "F.Fab")
		)
		(fp_line
			(start 0.12065 -0.3048)
			(end 0.67945 -0.3048)
			(stroke
				(width 0.1)
				(type default)
			)
			(layer "F.Fab")
		)
		(fp_line
			(start 0.12065 -0.2794)
			(end 0.12065 -0.3048)
			(stroke
				(width 0.1)
				(type default)
			)
			(layer "F.Fab")
		)
		(fp_line
			(start 0.67945 -0.3048)
			(end 0.67945 0.3048)
			(stroke
				(width 0.1)
				(type default)
			)
			(layer "F.Fab")
		)
		(fp_line
			(start 0.67945 0.3048)
			(end 0.120396 0.3048)
			(stroke
				(width 0.1)
				(type default)
			)
			(layer "F.Fab")
		)
		(pad "1" smd circle
			(at -0.40005 0)
			(size 0 0)
			(layers "F.Cu" "F.Mask" "F.Paste")
			(net "SW_P12V_P1V25_PEX3_FLT")
		)
		(pad "2" smd circle
			(at 0.40005 0)
			(size 0 0)
			(layers "F.Cu" "F.Mask" "F.Paste")
			(net "GND")
		)
	)
	(footprint ""
		(layer "F.Cu")
		(at 221.990158 -82.643472)
		(property "Reference" "R5767"
			(at 0 0 0)
			(layer "F.SilkS")
			(hide yes)
			(effects
				(font
					(size 1.27 1.27)
				)
			)
		)
		(property "Value" ""
			(at 0 0 0)
			(layer "F.Fab")
			(effects
				(font
					(size 1.27 1.27)
				)
			)
		)
		(duplicate_pad_numbers_are_jumpers no)
		(fp_line
			(start -0.7874 -0.4064)
			(end 0.7874 -0.4064)
			(stroke
				(width 0.1524)
				(type default)
			)
			(layer "F.SilkS")
		)
		(fp_line
			(start -0.7874 0.4064)
			(end -0.7874 -0.4064)
			(stroke
				(width 0.1524)
				(type default)
			)
			(layer "F.SilkS")
		)
		(fp_line
			(start 0.7874 -0.4064)
			(end 0.7874 0.4064)
			(stroke
				(width 0.1524)
				(type default)
			)
			(layer "F.SilkS")
		)
		(fp_line
			(start 0.7874 0.4064)
			(end -0.7874 0.4064)
			(stroke
				(width 0.1524)
				(type default)
			)
			(layer "F.SilkS")
		)
		(fp_line
			(start -0.67945 -0.305054)
			(end -0.12065 -0.305054)
			(stroke
				(width 0.1)
				(type default)
			)
			(layer "F.Fab")
		)
		(fp_line
			(start -0.67945 0.3048)
			(end -0.67945 -0.305054)
			(stroke
				(width 0.1)
				(type default)
			)
			(layer "F.Fab")
		)
		(fp_line
			(start -0.12065 -0.305054)
			(end -0.12065 -0.2794)
			(stroke
				(width 0.1)
				(type default)
			)
			(layer "F.Fab")
		)
		(fp_line
			(start -0.12065 -0.2794)
			(end 0.12065 -0.2794)
			(stroke
				(width 0.1)
				(type default)
			)
			(layer "F.Fab")
		)
		(fp_line
			(start -0.12065 0.2794)
			(end -0.12065 0.3048)
			(stroke
				(width 0.1)
				(type default)
			)
			(layer "F.Fab")
		)
		(fp_line
			(start -0.12065 0.3048)
			(end -0.67945 0.3048)
			(stroke
				(width 0.1)
				(type default)
			)
			(layer "F.Fab")
		)
		(fp_line
			(start 0.120396 0.2794)
			(end -0.12065 0.2794)
			(stroke
				(width 0.1)
				(type default)
			)
			(layer "F.Fab")
		)
		(fp_line
			(start 0.120396 0.3048)
			(end 0.120396 0.2794)
			(stroke
				(width 0.1)
				(type default)
			)
			(layer "F.Fab")
		)
		(fp_line
			(start 0.12065 -0.3048)
			(end 0.67945 -0.3048)
			(stroke
				(width 0.1)
				(type default)
			)
			(layer "F.Fab")
		)
		(fp_line
			(start 0.12065 -0.2794)
			(end 0.12065 -0.3048)
			(stroke
				(width 0.1)
				(type default)
			)
			(layer "F.Fab")
		)
		(fp_line
			(start 0.67945 -0.3048)
			(end 0.67945 0.3048)
			(stroke
				(width 0.1)
				(type default)
			)
			(layer "F.Fab")
		)
		(fp_line
			(start 0.67945 0.3048)
			(end 0.120396 0.3048)
			(stroke
				(width 0.1)
				(type default)
			)
			(layer "F.Fab")
		)
		(pad "1" smd circle
			(at -0.40005 0)
			(size 0 0)
			(layers "F.Cu" "F.Mask" "F.Paste")
			(net "SSD13_LED")
		)
		(pad "2" smd circle
			(at 0.40005 0)
			(size 0 0)
			(layers "F.Cu" "F.Mask" "F.Paste")
			(net "SSD13_LED_R")
		)
	)
	(footprint ""
		(layer "F.Cu")
		(at 82.526632 -53.697124 -90)
		(property "Reference" "PC498"
			(at 0 0 270)
			(layer "F.SilkS")
			(hide yes)
			(effects
				(font
					(size 1.27 1.27)
				)
			)
		)
		(property "Value" ""
			(at 0 0 270)
			(layer "F.Fab")
			(effects
				(font
					(size 1.27 1.27)
				)
			)
		)
		(duplicate_pad_numbers_are_jumpers no)
		(fp_line
			(start -0.7874 0.4064)
			(end -0.7874 -0.4064)
			(stroke
				(width 0.1524)
				(type default)
			)
			(layer "F.SilkS")
		)
		(fp_line
			(start 0.7874 0.4064)
			(end -0.7874 0.4064)
			(stroke
				(width 0.1524)
				(type default)
			)
			(layer "F.SilkS")
		)
		(fp_line
			(start -0.7874 -0.4064)
			(end 0.7874 -0.4064)
			(stroke
				(width 0.1524)
				(type default)
			)
			(layer "F.SilkS")
		)
		(fp_line
			(start 0.7874 -0.4064)
			(end 0.7874 0.4064)
			(stroke
				(width 0.1524)
				(type default)
			)
			(layer "F.SilkS")
		)
		(fp_line
			(start -0.67945 0.3048)
			(end -0.67945 -0.305054)
			(stroke
				(width 0.1)
				(type default)
			)
			(layer "F.Fab")
		)
		(fp_line
			(start -0.12065 0.3048)
			(end -0.67945 0.3048)
			(stroke
				(width 0.1)
				(type default)
			)
			(layer "F.Fab")
		)
		(fp_line
			(start 0.120396 0.3048)
			(end 0.120396 0.2794)
			(stroke
				(width 0.1)
				(type default)
			)
			(layer "F.Fab")
		)
		(fp_line
			(start 0.67945 0.3048)
			(end 0.120396 0.3048)
			(stroke
				(width 0.1)
				(type default)
			)
			(layer "F.Fab")
		)
		(fp_line
			(start -0.12065 0.2794)
			(end -0.12065 0.3048)
			(stroke
				(width 0.1)
				(type default)
			)
			(layer "F.Fab")
		)
		(fp_line
			(start 0.120396 0.2794)
			(end -0.12065 0.2794)
			(stroke
				(width 0.1)
				(type default)
			)
			(layer "F.Fab")
		)
		(fp_line
			(start -0.12065 -0.2794)
			(end 0.12065 -0.2794)
			(stroke
				(width 0.1)
				(type default)
			)
			(layer "F.Fab")
		)
		(fp_line
			(start 0.12065 -0.2794)
			(end 0.12065 -0.3048)
			(stroke
				(width 0.1)
				(type default)
			)
			(layer "F.Fab")
		)
		(fp_line
			(start 0.12065 -0.3048)
			(end 0.67945 -0.3048)
			(stroke
				(width 0.1)
				(type default)
			)
			(layer "F.Fab")
		)
		(fp_line
			(start 0.67945 -0.3048)
			(end 0.67945 0.3048)
			(stroke
				(width 0.1)
				(type default)
			)
			(layer "F.Fab")
		)
		(fp_line
			(start -0.67945 -0.305054)
			(end -0.12065 -0.305054)
			(stroke
				(width 0.1)
				(type default)
			)
			(layer "F.Fab")
		)
		(fp_line
			(start -0.12065 -0.305054)
			(end -0.12065 -0.2794)
			(stroke
				(width 0.1)
				(type default)
			)
			(layer "F.Fab")
		)
		(pad "1" smd circle
			(at -0.40005 0 270)
			(size 0 0)
			(layers "F.Cu" "F.Mask" "F.Paste")
			(net "P3V3_AUX")
		)
		(pad "2" smd circle
			(at 0.40005 0 270)
			(size 0 0)
			(layers "F.Cu" "F.Mask" "F.Paste")
			(net "GND")
		)
	)
	(footprint ""
		(layer "F.Cu")
		(at 435.494938 -59.577986 90)
		(property "Reference" "PC590"
			(at 0 0 90)
			(layer "F.SilkS")
			(hide yes)
			(effects
				(font
					(size 1.27 1.27)
				)
			)
		)
		(property "Value" ""
			(at 0 0 90)
			(layer "F.Fab")
			(effects
				(font
					(size 1.27 1.27)
				)
			)
		)
		(duplicate_pad_numbers_are_jumpers no)
		(fp_line
			(start 0.7874 -0.4064)
			(end 0.7874 0.4064)
			(stroke
				(width 0.1524)
				(type default)
			)
			(layer "F.SilkS")
		)
		(fp_line
			(start -0.7874 -0.4064)
			(end 0.7874 -0.4064)
			(stroke
				(width 0.1524)
				(type default)
			)
			(layer "F.SilkS")
		)
		(fp_line
			(start 0.7874 0.4064)
			(end -0.7874 0.4064)
			(stroke
				(width 0.1524)
				(type default)
			)
			(layer "F.SilkS")
		)
		(fp_line
			(start -0.7874 0.4064)
			(end -0.7874 -0.4064)
			(stroke
				(width 0.1524)
				(type default)
			)
			(layer "F.SilkS")
		)
		(fp_line
			(start -0.12065 -0.305054)
			(end -0.12065 -0.2794)
			(stroke
				(width 0.1)
				(type default)
			)
			(layer "F.Fab")
		)
		(fp_line
			(start -0.67945 -0.305054)
			(end -0.12065 -0.305054)
			(stroke
				(width 0.1)
				(type default)
			)
			(layer "F.Fab")
		)
		(fp_line
			(start 0.67945 -0.3048)
			(end 0.67945 0.3048)
			(stroke
				(width 0.1)
				(type default)
			)
			(layer "F.Fab")
		)
		(fp_line
			(start 0.12065 -0.3048)
			(end 0.67945 -0.3048)
			(stroke
				(width 0.1)
				(type default)
			)
			(layer "F.Fab")
		)
		(fp_line
			(start 0.12065 -0.2794)
			(end 0.12065 -0.3048)
			(stroke
				(width 0.1)
				(type default)
			)
			(layer "F.Fab")
		)
		(fp_line
			(start -0.12065 -0.2794)
			(end 0.12065 -0.2794)
			(stroke
				(width 0.1)
				(type default)
			)
			(layer "F.Fab")
		)
		(fp_line
			(start 0.120396 0.2794)
			(end -0.12065 0.2794)
			(stroke
				(width 0.1)
				(type default)
			)
			(layer "F.Fab")
		)
		(fp_line
			(start -0.12065 0.2794)
			(end -0.12065 0.3048)
			(stroke
				(width 0.1)
				(type default)
			)
			(layer "F.Fab")
		)
		(fp_line
			(start 0.67945 0.3048)
			(end 0.120396 0.3048)
			(stroke
				(width 0.1)
				(type default)
			)
			(layer "F.Fab")
		)
		(fp_line
			(start 0.120396 0.3048)
			(end 0.120396 0.2794)
			(stroke
				(width 0.1)
				(type default)
			)
			(layer "F.Fab")
		)
		(fp_line
			(start -0.12065 0.3048)
			(end -0.67945 0.3048)
			(stroke
				(width 0.1)
				(type default)
			)
			(layer "F.Fab")
		)
		(fp_line
			(start -0.67945 0.3048)
			(end -0.67945 -0.305054)
			(stroke
				(width 0.1)
				(type default)
			)
			(layer "F.Fab")
		)
		(pad "1" smd circle
			(at -0.40005 0 90)
			(size 0 0)
			(layers "F.Cu" "F.Mask" "F.Paste")
			(net "P3V3_SSD15_SS")
		)
		(pad "2" smd circle
			(at 0.40005 0 90)
			(size 0 0)
			(layers "F.Cu" "F.Mask" "F.Paste")
			(net "GND")
		)
	)
	(footprint ""
		(layer "F.Cu")
		(at 252.455172 -35.876738)
		(property "Reference" "R6081"
			(at 0 0 0)
			(layer "F.SilkS")
			(hide yes)
			(effects
				(font
					(size 1.27 1.27)
				)
			)
		)
		(property "Value" ""
			(at 0 0 0)
			(layer "F.Fab")
			(effects
				(font
					(size 1.27 1.27)
				)
			)
		)
		(duplicate_pad_numbers_are_jumpers no)
		(fp_line
			(start -0.7874 -0.4064)
			(end 0.7874 -0.4064)
			(stroke
				(width 0.1524)
				(type default)
			)
			(layer "F.SilkS")
		)
		(fp_line
			(start -0.7874 0.4064)
			(end -0.7874 -0.4064)
			(stroke
				(width 0.1524)
				(type default)
			)
			(layer "F.SilkS")
		)
		(fp_line
			(start 0.7874 -0.4064)
			(end 0.7874 0.4064)
			(stroke
				(width 0.1524)
				(type default)
			)
			(layer "F.SilkS")
		)
		(fp_line
			(start 0.7874 0.4064)
			(end -0.7874 0.4064)
			(stroke
				(width 0.1524)
				(type default)
			)
			(layer "F.SilkS")
		)
		(fp_line
			(start -0.67945 -0.305054)
			(end -0.12065 -0.305054)
			(stroke
				(width 0.1)
				(type default)
			)
			(layer "F.Fab")
		)
		(fp_line
			(start -0.67945 0.3048)
			(end -0.67945 -0.305054)
			(stroke
				(width 0.1)
				(type default)
			)
			(layer "F.Fab")
		)
		(fp_line
			(start -0.12065 -0.305054)
			(end -0.12065 -0.2794)
			(stroke
				(width 0.1)
				(type default)
			)
			(layer "F.Fab")
		)
		(fp_line
			(start -0.12065 -0.2794)
			(end 0.12065 -0.2794)
			(stroke
				(width 0.1)
				(type default)
			)
			(layer "F.Fab")
		)
		(fp_line
			(start -0.12065 0.2794)
			(end -0.12065 0.3048)
			(stroke
				(width 0.1)
				(type default)
			)
			(layer "F.Fab")
		)
		(fp_line
			(start -0.12065 0.3048)
			(end -0.67945 0.3048)
			(stroke
				(width 0.1)
				(type default)
			)
			(layer "F.Fab")
		)
		(fp_line
			(start 0.120396 0.2794)
			(end -0.12065 0.2794)
			(stroke
				(width 0.1)
				(type default)
			)
			(layer "F.Fab")
		)
		(fp_line
			(start 0.120396 0.3048)
			(end 0.120396 0.2794)
			(stroke
				(width 0.1)
				(type default)
			)
			(layer "F.Fab")
		)
		(fp_line
			(start 0.12065 -0.3048)
			(end 0.67945 -0.3048)
			(stroke
				(width 0.1)
				(type default)
			)
			(layer "F.Fab")
		)
		(fp_line
			(start 0.12065 -0.2794)
			(end 0.12065 -0.3048)
			(stroke
				(width 0.1)
				(type default)
			)
			(layer "F.Fab")
		)
		(fp_line
			(start 0.67945 -0.3048)
			(end 0.67945 0.3048)
			(stroke
				(width 0.1)
				(type default)
			)
			(layer "F.Fab")
		)
		(fp_line
			(start 0.67945 0.3048)
			(end 0.120396 0.3048)
			(stroke
				(width 0.1)
				(type default)
			)
			(layer "F.Fab")
		)
		(pad "1" smd circle
			(at -0.40005 0)
			(size 0 0)
			(layers "F.Cu" "F.Mask" "F.Paste")
			(net "P3V3_AUX")
		)
		(pad "2" smd circle
			(at 0.40005 0)
			(size 0 0)
			(layers "F.Cu" "F.Mask" "F.Paste")
			(net "PWRGD_P3V3_SSD9_D")
		)
	)
)
